(kicad_pcb
	(version 20260206)
	(generator "pcbnew")
	(generator_version "10.0")
	(general
		(thickness 1.6)
		(legacy_teardrops no)
	)
	(paper "A4")
	(title_block
		(title "Bryce Canyon_SCC_16316-1_OCP.brd")
		(comment 1 "Bryce Canyon / footprints 575-577 of 1561")
	)
	(layers
		(0 "F.Cu" signal "TOP")
		(4 "In1.Cu" signal "L2GND")
		(6 "In2.Cu" signal "L3")
		(8 "In3.Cu" signal "L4VCC")
		(10 "In4.Cu" signal "L5VCC")
		(12 "In5.Cu" signal "L6")
		(14 "In6.Cu" signal "L7GND")
		(2 "B.Cu" signal "BOTTOM")
		(9 "F.Adhes" user "F.Adhesive")
		(11 "B.Adhes" user "B.Adhesive")
		(13 "F.Paste" user "Package Geometry/Pastemask Top")
		(15 "B.Paste" user "Package Geometry/Pastemask Bottom")
		(5 "F.SilkS" user "Ref Des/Silkscreen Top")
		(7 "B.SilkS" user "Ref Des/Silkscreen Bottom")
		(1 "F.Mask" user "Board Geometry/Soldermask Top")
		(3 "B.Mask" user "Board Geometry/Soldermask Bottom")
		(17 "Dwgs.User" user "User.Drawings")
		(19 "Cmts.User" user "User.Comments")
		(21 "Eco1.User" user "User.Eco1")
		(23 "Eco2.User" user "User.Eco2")
		(25 "Edge.Cuts" user "Board Geometry/Outline")
		(27 "Margin" user)
		(31 "F.CrtYd" user "Package Geometry/Place Bound Top")
		(29 "B.CrtYd" user "Package Geometry/Place Bound Bottom")
		(35 "F.Fab" user "Ref Des/Assembly Top")
		(33 "B.Fab" user "Ref Des/Assembly Bottom")
	)
	(footprint ""
		(layer "F.Cu")
		(at 36.999926 -5.029962)
		(property "Reference" "CN1"
			(at 0 0 0)
			(layer "F.SilkS")
			(hide yes)
			(effects
				(font
					(size 1.27 1.27)
				)
			)
		)
		(property "Value" "AMP-CONN12-2R-2-GP"
			(at -22.010116 -12.120118 0)
			(unlocked yes)
			(layer "F.Fab")
			(hide yes)
			(effects
				(font
					(size 1.016 1.016)
					(thickness 0.1524)
				)
			)
		)
		(property "Device Type" "PREFIT-12P-162281H396"
			(at -22.010116 -13.644118 0)
			(unlocked yes)
			(layer "F.Fab")
			(hide yes)
			(effects
				(font
					(size 1.016 1.016)
					(thickness 0.1524)
				)
			)
		)
		(duplicate_pad_numbers_are_jumpers no)
		(fp_line
			(start -11.2522 -11.1506)
			(end -11.2522 5.029962)
			(stroke
				(width 0.1524)
				(type default)
			)
			(layer "F.SilkS")
		)
		(fp_line
			(start -11.2522 5.029962)
			(end 5.4356 5.029962)
			(stroke
				(width 0.1524)
				(type default)
			)
			(layer "F.SilkS")
		)
		(fp_line
			(start 5.4356 -11.1506)
			(end -11.2522 -11.1506)
			(stroke
				(width 0.1524)
				(type default)
			)
			(layer "F.SilkS")
		)
		(fp_line
			(start 5.4356 5.029962)
			(end 5.4356 -11.1506)
			(stroke
				(width 0.1524)
				(type default)
			)
			(layer "F.SilkS")
		)
		(fp_poly
			(pts
				(arc
					(start 0.259588 2.049272)
					(mid 0.005588 2.303272)
					(end -0.248412 2.049272)
				)
				(arc
					(start -0.248412 1.287272)
					(mid 0.005588 1.033272)
					(end 0.259588 1.287272)
				)
			)
			(stroke
				(width 0)
				(type default)
			)
			(fill yes)
			(layer "F.SilkS")
		)
		(fp_poly
			(pts
				(arc
					(start 3.510788 2.049272)
					(mid 3.256788 2.303272)
					(end 3.002788 2.049272)
				)
				(arc
					(start 3.002788 1.287272)
					(mid 3.256788 1.033272)
					(end 3.510788 1.287272)
				)
			)
			(stroke
				(width 0)
				(type default)
			)
			(fill yes)
			(layer "F.SilkS")
		)
		(fp_poly
			(pts
				(xy -11.2522 5.029962) (xy -11.2522 -11.1506) (xy -5.3086 -11.1506) (xy -5.3086 -9.312656) (xy -0.8128 -9.312656)
				(xy -0.8128 -4.9784)
				(arc
					(start -5.98551 -4.9784)
					(mid -9.0527 -4.788153)
					(end -5.984748 -4.9657)
				)
				(xy -0.8128 -4.9657) (xy -0.8128 0.6477)
				(arc
					(start -6.185662 0.6477)
					(mid -8.862964 1.994161)
					(end -6.179312 0.6604)
				)
				(xy -0.8128 0.6604) (xy -0.8128 0.8128) (xy -0.4445 0.8128) (xy -0.4445 2.4257) (xy 3.683 2.4257)
				(xy 3.683 0.8128) (xy 4.012692 0.8128) (xy 4.012692 -9.312656) (xy 5.4356 -9.312656) (xy 5.4356 5.029962)
			)
			(stroke
				(width 0)
				(type default)
			)
			(fill yes)
			(layer "F.SilkS")
		)
		(fp_rect
			(start -5.6134 5.6134)
			(end 8.8138 -14.1224)
			(stroke
				(width 0)
				(type default)
			)
			(fill no)
			(layer "B.CrtYd")
		)
		(fp_rect
			(start -10.9982 17.1958)
			(end 5.1816 -10.8966)
			(stroke
				(width 0)
				(type default)
			)
			(fill no)
			(layer "F.CrtYd")
		)
		(fp_poly
			(pts
				(xy -16.002 22.1996) (xy -16.002 -15.9004) (xy 10.1854 -15.9004) (xy 10.1854 -0.00635) (xy 5.6896 -0.00635)
				(xy 5.6896 -11.4046) (xy -11.5062 -11.4046) (xy -11.5062 17.7038) (xy 5.6896 17.7038) (xy 5.6896 0.00635)
				(xy 10.1854 0.00635) (xy 10.1854 22.1996)
			)
			(stroke
				(width 0)
				(type default)
			)
			(fill no)
			(layer "F.CrtYd")
		)
		(fp_poly
			(pts
				(xy -11.5062 17.7038) (xy -11.5062 -11.4046) (xy 5.6896 -11.4046) (xy 5.6896 -0.00635) (xy 5.1816 -0.00635)
				(xy 5.1816 -10.8966) (xy -10.9982 -10.8966) (xy -10.9982 17.1958) (xy 5.1816 17.1958) (xy 5.1816 0.00635)
				(xy 5.6896 0.00635) (xy 5.6896 17.7038)
			)
			(stroke
				(width 0)
				(type default)
			)
			(fill no)
			(layer "F.CrtYd")
		)
		(fp_rect
			(start -10.6172 10.6172)
			(end 13.8176 -19.1262)
			(stroke
				(width 0)
				(type default)
			)
			(fill no)
			(layer "B.Fab")
		)
		(fp_rect
			(start -5.6134 5.6134)
			(end 8.8138 -14.1224)
			(stroke
				(width 0)
				(type default)
			)
			(fill no)
			(layer "B.Fab")
		)
		(fp_rect
			(start -21.0058 27.2034)
			(end 15.1892 -20.9042)
			(stroke
				(width 0)
				(type default)
			)
			(fill no)
			(layer "F.Fab")
		)
		(fp_rect
			(start -16.002 22.1996)
			(end 10.1854 -15.9004)
			(stroke
				(width 0)
				(type default)
			)
			(fill no)
			(layer "F.Fab")
		)
		(fp_rect
			(start -11.5062 17.7038)
			(end 5.6896 -11.4046)
			(stroke
				(width 0)
				(type default)
			)
			(fill no)
			(layer "F.Fab")
		)
		(fp_text user "Press fit"
			(at -5.0546 -10.1854 0)
			(unlocked yes)
			(layer "F.SilkS")
			(effects
				(font
					(size 1.016 1.016)
					(thickness 0.1524)
				)
				(justify left)
			)
		)
		(fp_text user "Slit"
			(at -4.868926 6.985762 0)
			(unlocked yes)
			(layer "F.SilkS")
			(effects
				(font
					(size 1.016 1.016)
					(thickness 0.1524)
				)
				(justify left)
			)
		)
		(fp_text user "Can not place BGA,CSP,Wave Solder Component"
			(at -28.482798 9.450578 0)
			(unlocked yes)
			(layer "B.Fab")
			(effects
				(font
					(size 1.016 1.016)
					(thickness 0.1524)
				)
				(justify left)
			)
		)
		(fp_text user "Can not place BGA,CSP,Wave Solder Component"
			(at -27.338528 25.206452 0)
			(unlocked yes)
			(layer "F.Fab")
			(effects
				(font
					(size 1.016 1.016)
					(thickness 0.1524)
				)
				(justify left)
			)
		)
		(fp_text user "High Limt 2mm"
			(at -10.438638 20.365212 0)
			(unlocked yes)
			(layer "F.Fab")
			(effects
				(font
					(size 1.016 1.016)
					(thickness 0.1524)
				)
				(justify left)
			)
		)
		(pad "" np_thru_hole circle
			(at -7.519924 -4.895088)
			(size 0.254 0.254)
			(drill 2.4638)
			(layers "*.Cu" "*.Mask")
			(clearance 1.4605)
			(thermal_gap 1.4605)
		)
		(pad "" np_thru_hole circle
			(at -7.519924 1.329944)
			(size 0.254 0.254)
			(drill 2.3876)
			(layers "*.Cu" "*.Mask")
			(clearance 1.4224)
			(thermal_gap 1.4224)
		)
		(pad "A1" thru_hole circle
			(at 0 0)
			(size 1.2192 1.2192)
			(drill 0.739902)
			(layers "*.Cu" "*.Mask")
			(remove_unused_layers no)
			(net "P12V_MAIN")
			(clearance 0.127)
			(thermal_gap 0.127)
		)
		(pad "A2" thru_hole oval
			(at 0 -1.49987)
			(size 1.2192 4.2164)
			(drill 0.739902)
			(layers "*.Cu" "*.Mask")
			(remove_unused_layers no)
			(net "P12V_MAIN")
			(clearance 0.127)
			(thermal_gap 0.127)
			(padstack
				(mode front_inner_back)
				(layer "Inner"
					(shape circle)
					(size 1.2192 1.2192)
					(clearance 0.127)
				)
				(layer "B.Cu"
					(shape circle)
					(size 1.2192 1.2192)
					(clearance 0.127)
				)
			)
		)
		(pad "A3" thru_hole circle
			(at 0 -2.999994)
			(size 1.2192 1.2192)
			(drill 0.739902)
			(layers "*.Cu" "*.Mask")
			(remove_unused_layers no)
			(net "P12V_MAIN")
			(clearance 0.127)
			(thermal_gap 0.127)
		)
		(pad "A4" thru_hole circle
			(at 0 -5.499862)
			(size 1.2192 1.2192)
			(drill 0.739902)
			(layers "*.Cu" "*.Mask")
			(remove_unused_layers no)
			(net "P12V_MAIN")
			(clearance 0.127)
			(thermal_gap 0.127)
		)
		(pad "A5" thru_hole oval
			(at 0 -6.999986)
			(size 1.2192 4.2164)
			(drill 0.739902)
			(layers "*.Cu" "*.Mask")
			(remove_unused_layers no)
			(net "P12V_MAIN")
			(clearance 0.127)
			(thermal_gap 0.127)
			(padstack
				(mode front_inner_back)
				(layer "Inner"
					(shape circle)
					(size 1.2192 1.2192)
					(clearance 0.127)
				)
				(layer "B.Cu"
					(shape circle)
					(size 1.2192 1.2192)
					(clearance 0.127)
				)
			)
		)
		(pad "A6" thru_hole circle
			(at 0 -8.499856)
			(size 1.2192 1.2192)
			(drill 0.739902)
			(layers "*.Cu" "*.Mask")
			(remove_unused_layers no)
			(net "P12V_MAIN")
			(clearance 0.127)
			(thermal_gap 0.127)
		)
		(pad "B1" thru_hole circle
			(at 3.199892 0)
			(size 1.2192 1.2192)
			(drill 0.739902)
			(layers "*.Cu" "*.Mask")
			(remove_unused_layers no)
			(net "GND")
			(clearance 0.127)
			(thermal_gap 0.127)
		)
		(pad "B2" thru_hole oval
			(at 3.199892 -1.49987)
			(size 1.2192 4.2164)
			(drill 0.739902)
			(layers "*.Cu" "*.Mask")
			(remove_unused_layers no)
			(net "GND")
			(clearance 0.127)
			(thermal_gap 0.127)
			(padstack
				(mode front_inner_back)
				(layer "Inner"
					(shape circle)
					(size 1.2192 1.2192)
					(clearance 0.127)
				)
				(layer "B.Cu"
					(shape circle)
					(size 1.2192 1.2192)
					(clearance 0.127)
				)
			)
		)
		(pad "B3" thru_hole circle
			(at 3.199892 -2.999994)
			(size 1.2192 1.2192)
			(drill 0.739902)
			(layers "*.Cu" "*.Mask")
			(remove_unused_layers no)
			(net "GND")
			(clearance 0.127)
			(thermal_gap 0.127)
		)
		(pad "B4" thru_hole circle
			(at 3.199892 -5.499862)
			(size 1.2192 1.2192)
			(drill 0.739902)
			(layers "*.Cu" "*.Mask")
			(remove_unused_layers no)
			(net "GND")
			(clearance 0.127)
			(thermal_gap 0.127)
		)
		(pad "B5" thru_hole oval
			(at 3.199892 -6.999986)
			(size 1.2192 4.2164)
			(drill 0.739902)
			(layers "*.Cu" "*.Mask")
			(remove_unused_layers no)
			(net "GND")
			(clearance 0.127)
			(thermal_gap 0.127)
			(padstack
				(mode front_inner_back)
				(layer "Inner"
					(shape circle)
					(size 1.2192 1.2192)
					(clearance 0.127)
				)
				(layer "B.Cu"
					(shape circle)
					(size 1.2192 1.2192)
					(clearance 0.127)
				)
			)
		)
		(pad "B6" thru_hole circle
			(at 3.199892 -8.499856)
			(size 1.2192 1.2192)
			(drill 0.739902)
			(layers "*.Cu" "*.Mask")
			(remove_unused_layers no)
			(net "GND")
			(clearance 0.127)
			(thermal_gap 0.127)
		)
		(zone
			(layer "F.Cu")
			(hatch none 0.5)
			(connect_pads
				(clearance 0)
			)
			(min_thickness 0.25)
			(keepout
				(tracks allowed)
				(vias not_allowed)
				(pads allowed)
				(copperpour not_allowed)
				(footprints allowed)
			)
			(placement
				(enabled no)
				(sheetname "")
			)
			(fill
				(thermal_gap 0.5)
				(thermal_bridge_width 0.5)
				(island_removal_mode 0)
			)
			(polygon
				(pts
					(xy 26.159968 0) (xy 32.759904 0) (xy 32.759904 -15.929864) (xy 26.159968 -15.929864)
				)
			)
		)
		(zone
			(layer "F.Cu")
			(hatch none 0.5)
			(connect_pads
				(clearance 0)
			)
			(min_thickness 0.25)
			(keepout
				(tracks not_allowed)
				(vias allowed)
				(pads allowed)
				(copperpour not_allowed)
				(footprints allowed)
			)
			(placement
				(enabled no)
				(sheetname "")
			)
			(fill
				(thermal_gap 0.5)
				(thermal_bridge_width 0.5)
				(island_removal_mode 0)
			)
			(polygon
				(pts
					(xy 26.159968 0) (xy 32.759904 0) (xy 32.759904 -15.929864) (xy 26.159968 -15.929864)
				)
			)
		)
		(zone
			(layer "F.Cu")
			(hatch none 0.5)
			(connect_pads
				(clearance 0)
			)
			(min_thickness 0.25)
			(keepout
				(tracks allowed)
				(vias not_allowed)
				(pads allowed)
				(copperpour not_allowed)
				(footprints allowed)
			)
			(placement
				(enabled no)
				(sheetname "")
			)
			(fill
				(thermal_gap 0.5)
				(thermal_bridge_width 0.5)
				(island_removal_mode 0)
			)
			(polygon
				(pts
					(xy 36.150042 -14.379956) (xy 36.150042 -4.180078) (xy 41.049956 -4.180078) (xy 41.049956 -14.379956)
				)
			)
		)
		(zone
			(layer "F.Cu")
			(hatch none 0.5)
			(connect_pads
				(clearance 0)
			)
			(min_thickness 0.25)
			(keepout
				(tracks not_allowed)
				(vias allowed)
				(pads allowed)
				(copperpour not_allowed)
				(footprints allowed)
			)
			(placement
				(enabled no)
				(sheetname "")
			)
			(fill
				(thermal_gap 0.5)
				(thermal_bridge_width 0.5)
				(island_removal_mode 0)
			)
			(polygon
				(pts
					(xy 36.150042 -4.180078) (xy 41.049956 -4.180078) (xy 41.049956 -14.379956) (xy 36.150042 -14.379956)
				)
			)
		)
		(zone
			(layers "F.Cu" "B.Cu" "In1.Cu" "In2.Cu" "In3.Cu" "In4.Cu" "In5.Cu" "In6.Cu")
			(hatch none 0.5)
			(connect_pads
				(clearance 0)
			)
			(min_thickness 0.25)
			(keepout
				(tracks not_allowed)
				(vias allowed)
				(pads allowed)
				(copperpour not_allowed)
				(footprints allowed)
			)
			(placement
				(enabled no)
				(sheetname "")
			)
			(fill
				(thermal_gap 0.5)
				(thermal_bridge_width 0.5)
				(island_removal_mode 0)
			)
			(polygon
				(pts
					(arc
						(start 30.978602 -3.700018)
						(mid 27.981402 -3.700018)
						(end 30.978602 -3.700018)
					)
				)
			)
		)
		(zone
			(layers "F.Cu" "B.Cu" "In1.Cu" "In2.Cu" "In3.Cu" "In4.Cu" "In5.Cu" "In6.Cu")
			(hatch none 0.5)
			(connect_pads
				(clearance 0)
			)
			(min_thickness 0.25)
			(keepout
				(tracks not_allowed)
				(vias allowed)
				(pads allowed)
				(copperpour not_allowed)
				(footprints allowed)
			)
			(placement
				(enabled no)
				(sheetname "")
			)
			(fill
				(thermal_gap 0.5)
				(thermal_bridge_width 0.5)
				(island_removal_mode 0)
			)
			(polygon
				(pts
					(arc
						(start 31.016702 -9.92505)
						(mid 27.943302 -9.92505)
						(end 31.016702 -9.92505)
					)
				)
			)
		)
	)
	(footprint ""
		(layer "F.Cu")
		(at 68.9864 -72.6948)
		(property "Reference" "R427"
			(at 0 0 0)
			(layer "F.SilkS")
			(hide yes)
			(effects
				(font
					(size 1.27 1.27)
				)
			)
		)
		(property "Value" "200KR2F-L-GP"
			(at 0.064008 -3.993896 0)
			(unlocked yes)
			(layer "F.Fab")
			(hide yes)
			(effects
				(font
					(size 1.016 1.016)
					(thickness 0.1524)
				)
			)
		)
		(property "Device Type" "R402H16"
			(at 0.064008 -5.517896 0)
			(unlocked yes)
			(layer "F.Fab")
			(hide yes)
			(effects
				(font
					(size 1.016 1.016)
					(thickness 0.1524)
				)
			)
		)
		(duplicate_pad_numbers_are_jumpers no)
		(fp_line
			(start -0.508 -0.9398)
			(end -0.508 0.9398)
			(stroke
				(width 0.1524)
				(type default)
			)
			(layer "F.SilkS")
		)
		(fp_line
			(start 0.508 -0.9398)
			(end -0.508 -0.9398)
			(stroke
				(width 0.1524)
				(type default)
			)
			(layer "F.SilkS")
		)
		(fp_rect
			(start -0.508 0.9398)
			(end 0.508 -0.9398)
			(stroke
				(width 0)
				(type default)
			)
			(fill no)
			(layer "F.CrtYd")
		)
		(fp_rect
			(start -0.508 0.9398)
			(end 0.508 -0.9398)
			(stroke
				(width 0)
				(type default)
			)
			(fill no)
			(layer "F.Fab")
		)
		(pad "1" smd custom
			(at 0 -0.4445)
			(size 0.1397 0.1397)
			(layers "F.Cu" "F.Mask" "F.Paste")
			(net "VREF6")
			(options
				(clearance outline)
				(anchor circle)
			)
			(primitives
				(gr_poly
					(pts
						(arc
							(start -0.1778 -0.2794)
							(mid -0.249642 -0.249642)
							(end -0.2794 -0.1778)
						)
						(arc
							(start -0.2794 0.1778)
							(mid -0.249642 0.249642)
							(end -0.1778 0.2794)
						)
						(arc
							(start 0.1778 0.2794)
							(mid 0.249642 0.249642)
							(end 0.2794 0.1778)
						)
						(arc
							(start 0.2794 -0.1778)
							(mid 0.249642 -0.249642)
							(end 0.1778 -0.2794)
						)
					)
					(width 0)
					(fill yes)
				)
			)
		)
		(pad "2" smd custom
			(at 0 0.4445)
			(size 0.1397 0.1397)
			(layers "F.Cu" "F.Mask" "F.Paste")
			(net "P3V3")
			(options
				(clearance outline)
				(anchor circle)
			)
			(primitives
				(gr_poly
					(pts
						(arc
							(start -0.1778 -0.2794)
							(mid -0.249642 -0.249642)
							(end -0.2794 -0.1778)
						)
						(arc
							(start -0.2794 0.1778)
							(mid -0.249642 0.249642)
							(end -0.1778 0.2794)
						)
						(arc
							(start 0.1778 0.2794)
							(mid 0.249642 0.249642)
							(end 0.2794 0.1778)
						)
						(arc
							(start 0.2794 -0.1778)
							(mid 0.249642 -0.249642)
							(end 0.1778 -0.2794)
						)
					)
					(width 0)
					(fill yes)
				)
			)
		)
	)
	(footprint ""
		(layer "F.Cu")
		(at 56.89473 -17.396714)
		(property "Reference" "C741"
			(at 0 0 0)
			(layer "F.SilkS")
			(hide yes)
			(effects
				(font
					(size 1.27 1.27)
				)
			)
		)
		(property "Value" "SCD1U16V2KX-3GP"
			(at 1.1811 -2.7051 0)
			(unlocked yes)
			(layer "F.Fab")
			(hide yes)
			(effects
				(font
					(size 1.016 1.016)
					(thickness 0.1524)
				)
			)
		)
		(property "Device Type" "C402H22"
			(at 1.1811 -4.2291 0)
			(unlocked yes)
			(layer "F.Fab")
			(hide yes)
			(effects
				(font
					(size 1.016 1.016)
					(thickness 0.1524)
				)
			)
		)
		(duplicate_pad_numbers_are_jumpers no)
		(fp_rect
			(start -0.4318 0.9525)
			(end 0.4318 -0.9525)
			(stroke
				(width 0)
				(type default)
			)
			(fill no)
			(layer "F.CrtYd")
		)
		(fp_rect
			(start -0.4318 0.9525)
			(end 0.4318 -0.9525)
			(stroke
				(width 0)
				(type default)
			)
			(fill no)
			(layer "F.Fab")
		)
		(pad "1" smd custom
			(at 0 -0.4445)
			(size 0.1524 0.1524)
			(layers "F.Cu" "F.Mask" "F.Paste")
			(net "U47_OE")
			(options
				(clearance outline)
				(anchor circle)
			)
			(primitives
				(gr_poly
					(pts
						(arc
							(start 0.3048 -0.2032)
							(mid 0.275042 -0.275042)
							(end 0.2032 -0.3048)
						)
						(arc
							(start -0.2032 -0.3048)
							(mid -0.275042 -0.275042)
							(end -0.3048 -0.2032)
						)
						(arc
							(start -0.3048 0.2032)
							(mid -0.275042 0.275042)
							(end -0.2032 0.3048)
						)
						(arc
							(start 0.2032 0.3048)
							(mid 0.275042 0.275042)
							(end 0.3048 0.2032)
						)
					)
					(width 0)
					(fill yes)
				)
			)
		)
		(pad "2" smd custom
			(at 0 0.4445)
			(size 0.1524 0.1524)
			(layers "F.Cu" "F.Mask" "F.Paste")
			(net "GND")
			(options
				(clearance outline)
				(anchor circle)
			)
			(primitives
				(gr_poly
					(pts
						(arc
							(start 0.3048 -0.2032)
							(mid 0.275042 -0.275042)
							(end 0.2032 -0.3048)
						)
						(arc
							(start -0.2032 -0.3048)
							(mid -0.275042 -0.275042)
							(end -0.3048 -0.2032)
						)
						(arc
							(start -0.3048 0.2032)
							(mid -0.275042 0.275042)
							(end -0.2032 0.3048)
						)
						(arc
							(start 0.2032 0.3048)
							(mid 0.275042 0.275042)
							(end 0.3048 0.2032)
						)
					)
					(width 0)
					(fill yes)
				)
			)
		)
	)
)
